(kicad_pcb
	(version 20260206)
	(generator "pcbnew")
	(generator_version "10.0")
	(general
		(thickness 1.6)
		(legacy_teardrops no)
	)
	(paper "A4")
	(title_block
		(title "panther-plus-userver — 13130-1b_20150205.brd")
		(comment 1 "Honey Badger (Wiwynn) / footprints 113-120 of 1509")
	)
	(layers
		(0 "F.Cu" signal "TOP")
		(4 "In1.Cu" signal "L2")
		(6 "In2.Cu" signal "L3")
		(8 "In3.Cu" signal "L4")
		(10 "In4.Cu" signal "L5")
		(12 "In5.Cu" signal "L6")
		(14 "In6.Cu" signal "L7")
		(16 "In7.Cu" signal "L8")
		(18 "In8.Cu" signal "L9")
		(20 "In9.Cu" signal "L10")
		(22 "In10.Cu" signal "L11")
		(2 "B.Cu" signal "BOTTOM")
		(9 "F.Adhes" user "F.Adhesive")
		(11 "B.Adhes" user "B.Adhesive")
		(13 "F.Paste" user "Package Geometry/Pastemask Top")
		(15 "B.Paste" user "Package Geometry/Pastemask Bottom")
		(5 "F.SilkS" user "Ref Des/Silkscreen Top")
		(7 "B.SilkS" user "Ref Des/Silkscreen Bottom")
		(1 "F.Mask" user "Board Geometry/Soldermask Top")
		(3 "B.Mask" user "Board Geometry/Soldermask Bottom")
		(17 "Dwgs.User" user "User.Drawings")
		(19 "Cmts.User" user "User.Comments")
		(21 "Eco1.User" user "User.Eco1")
		(23 "Eco2.User" user "User.Eco2")
		(25 "Edge.Cuts" user "Board Geometry/Outline")
		(27 "Margin" user)
		(31 "F.CrtYd" user "Package Geometry/Place Bound Top")
		(29 "B.CrtYd" user "Package Geometry/Place Bound Bottom")
		(35 "F.Fab" user "Ref Des/Assembly Top")
		(33 "B.Fab" user "Ref Des/Assembly Bottom")
	)
	(footprint ""
		(layer "F.Cu")
		(at 203.962 -66.1924 90)
		(property "Reference" "PC169"
			(at 0 0 90)
			(layer "F.SilkS")
			(hide yes)
			(effects
				(font
					(size 1.27 1.27)
				)
			)
		)
		(property "Value" "SC10U6D3V3MX-GP"
			(at -0.0254 -2.0193 90)
			(unlocked yes)
			(layer "F.Fab")
			(hide yes)
			(effects
				(font
					(size 1.016 1.016)
					(thickness 0.1524)
				)
			)
		)
		(property "Device Type" "C603H38"
			(at -0.0254 -3.5433 90)
			(unlocked yes)
			(layer "F.Fab")
			(hide yes)
			(effects
				(font
					(size 1.016 1.016)
					(thickness 0.1524)
				)
			)
		)
		(duplicate_pad_numbers_are_jumpers no)
		(fp_line
			(start -0.4064 0)
			(end 0.4064 0)
			(stroke
				(width 0.2286)
				(type default)
			)
			(layer "F.SilkS")
		)
		(fp_rect
			(start -0.635 1.1811)
			(end 0.635 -1.1811)
			(stroke
				(width 0)
				(type default)
			)
			(fill no)
			(layer "F.CrtYd")
		)
		(fp_rect
			(start -0.635 1.1811)
			(end 0.635 -1.1811)
			(stroke
				(width 0)
				(type default)
			)
			(fill no)
			(layer "F.Fab")
		)
		(pad "1" smd custom
			(at 0 -0.6604 90)
			(size 0.19685 0.19685)
			(layers "F.Cu" "F.Mask" "F.Paste")
			(net "PV_VDDR")
			(options
				(clearance outline)
				(anchor circle)
			)
			(primitives
				(gr_poly
					(pts
						(arc
							(start 0.508 -0.2921)
							(mid 0.478242 -0.363942)
							(end 0.4064 -0.3937)
						)
						(arc
							(start -0.4064 -0.3937)
							(mid -0.478242 -0.363942)
							(end -0.508 -0.2921)
						)
						(arc
							(start -0.508 0.2921)
							(mid -0.478242 0.363942)
							(end -0.4064 0.3937)
						)
						(arc
							(start 0.4064 0.3937)
							(mid 0.478242 0.363942)
							(end 0.508 0.2921)
						)
					)
					(width 0)
					(fill yes)
				)
			)
		)
		(pad "2" smd custom
			(at 0 0.6604 90)
			(size 0.19685 0.19685)
			(layers "F.Cu" "F.Mask" "F.Paste")
			(net "GND")
			(options
				(clearance outline)
				(anchor circle)
			)
			(primitives
				(gr_poly
					(pts
						(arc
							(start 0.508 -0.2921)
							(mid 0.478242 -0.363942)
							(end 0.4064 -0.3937)
						)
						(arc
							(start -0.4064 -0.3937)
							(mid -0.478242 -0.363942)
							(end -0.508 -0.2921)
						)
						(arc
							(start -0.508 0.2921)
							(mid -0.478242 0.363942)
							(end -0.4064 0.3937)
						)
						(arc
							(start 0.4064 0.3937)
							(mid 0.478242 0.363942)
							(end 0.508 0.2921)
						)
					)
					(width 0)
					(fill yes)
				)
			)
		)
	)
	(footprint ""
		(layer "F.Cu")
		(at 52.9844 -12.827 180)
		(property "Reference" "C316"
			(at 0 0 180)
			(layer "F.SilkS")
			(hide yes)
			(effects
				(font
					(size 1.27 1.27)
				)
			)
		)
		(property "Value" "SCD047U25V2KX-GP"
			(at 1.8923 -1.2065 180)
			(unlocked yes)
			(layer "F.Fab")
			(hide yes)
			(effects
				(font
					(size 1.016 1.016)
					(thickness 0.1524)
				)
			)
		)
		(property "Device Type" "C402H22"
			(at 1.8923 -2.7305 180)
			(unlocked yes)
			(layer "F.Fab")
			(hide yes)
			(effects
				(font
					(size 1.016 1.016)
					(thickness 0.1524)
				)
			)
		)
		(duplicate_pad_numbers_are_jumpers no)
		(fp_rect
			(start -0.381 0.7366)
			(end 0.381 -0.7366)
			(stroke
				(width 0)
				(type default)
			)
			(fill no)
			(layer "F.CrtYd")
		)
		(fp_rect
			(start -0.381 0.7366)
			(end 0.381 -0.7366)
			(stroke
				(width 0)
				(type default)
			)
			(fill no)
			(layer "F.Fab")
		)
		(pad "1" smd custom
			(at 0 -0.4572 180)
			(size 0.1143 0.1143)
			(layers "F.Cu" "F.Mask" "F.Paste")
			(net "CPU_GBE_RX_C_DP0")
			(options
				(clearance outline)
				(anchor circle)
			)
			(primitives
				(gr_poly
					(pts
						(arc
							(start -0.254 -0.1778)
							(mid -0.239121 -0.213721)
							(end -0.2032 -0.2286)
						)
						(arc
							(start 0.2032 -0.2286)
							(mid 0.239121 -0.213721)
							(end 0.254 -0.1778)
						)
						(arc
							(start 0.254 0.1778)
							(mid 0.239121 0.213721)
							(end 0.2032 0.2286)
						)
						(arc
							(start -0.2032 0.2286)
							(mid -0.239121 0.213721)
							(end -0.254 0.1778)
						)
					)
					(width 0)
					(fill yes)
				)
			)
		)
		(pad "2" smd custom
			(at 0 0.4572 180)
			(size 0.1143 0.1143)
			(layers "F.Cu" "F.Mask" "F.Paste")
			(net "CPU_GBE_RX_DP0")
			(options
				(clearance outline)
				(anchor circle)
			)
			(primitives
				(gr_poly
					(pts
						(arc
							(start -0.254 -0.1778)
							(mid -0.239121 -0.213721)
							(end -0.2032 -0.2286)
						)
						(arc
							(start 0.2032 -0.2286)
							(mid 0.239121 -0.213721)
							(end 0.254 -0.1778)
						)
						(arc
							(start 0.254 0.1778)
							(mid 0.239121 0.213721)
							(end 0.2032 0.2286)
						)
						(arc
							(start -0.2032 0.2286)
							(mid -0.239121 0.213721)
							(end -0.254 0.1778)
						)
					)
					(width 0)
					(fill yes)
				)
			)
		)
	)
	(footprint ""
		(layer "F.Cu")
		(at 182.118 -48.768)
		(property "Reference" "C95"
			(at 0 0 0)
			(layer "F.SilkS")
			(hide yes)
			(effects
				(font
					(size 1.27 1.27)
				)
			)
		)
		(property "Value" "SCD1U16V2KX-3GP"
			(at 1.1811 -2.7051 0)
			(unlocked yes)
			(layer "F.Fab")
			(hide yes)
			(effects
				(font
					(size 1.016 1.016)
					(thickness 0.1524)
				)
			)
		)
		(property "Device Type" "C402H22"
			(at 1.1811 -4.2291 0)
			(unlocked yes)
			(layer "F.Fab")
			(hide yes)
			(effects
				(font
					(size 1.016 1.016)
					(thickness 0.1524)
				)
			)
		)
		(duplicate_pad_numbers_are_jumpers no)
		(fp_rect
			(start -0.381 0.7366)
			(end 0.381 -0.7366)
			(stroke
				(width 0)
				(type default)
			)
			(fill no)
			(layer "F.CrtYd")
		)
		(fp_rect
			(start -0.381 0.7366)
			(end 0.381 -0.7366)
			(stroke
				(width 0)
				(type default)
			)
			(fill no)
			(layer "F.Fab")
		)
		(pad "1" smd custom
			(at 0 -0.4572)
			(size 0.1143 0.1143)
			(layers "F.Cu" "F.Mask" "F.Paste")
			(net "P3V3_STBY")
			(options
				(clearance outline)
				(anchor circle)
			)
			(primitives
				(gr_poly
					(pts
						(arc
							(start -0.254 -0.1778)
							(mid -0.239121 -0.213721)
							(end -0.2032 -0.2286)
						)
						(arc
							(start 0.2032 -0.2286)
							(mid 0.239121 -0.213721)
							(end 0.254 -0.1778)
						)
						(arc
							(start 0.254 0.1778)
							(mid 0.239121 0.213721)
							(end 0.2032 0.2286)
						)
						(arc
							(start -0.2032 0.2286)
							(mid -0.239121 0.213721)
							(end -0.254 0.1778)
						)
					)
					(width 0)
					(fill yes)
				)
			)
		)
		(pad "2" smd custom
			(at 0 0.4572)
			(size 0.1143 0.1143)
			(layers "F.Cu" "F.Mask" "F.Paste")
			(net "GND")
			(options
				(clearance outline)
				(anchor circle)
			)
			(primitives
				(gr_poly
					(pts
						(arc
							(start -0.254 -0.1778)
							(mid -0.239121 -0.213721)
							(end -0.2032 -0.2286)
						)
						(arc
							(start 0.2032 -0.2286)
							(mid 0.239121 -0.213721)
							(end 0.254 -0.1778)
						)
						(arc
							(start 0.254 0.1778)
							(mid 0.239121 0.213721)
							(end 0.2032 0.2286)
						)
						(arc
							(start -0.2032 0.2286)
							(mid -0.239121 0.213721)
							(end -0.254 0.1778)
						)
					)
					(width 0)
					(fill yes)
				)
			)
		)
	)
	(footprint ""
		(layer "F.Cu")
		(at 187.96 -59.944)
		(property "Reference" "C353"
			(at 0 0 0)
			(layer "F.SilkS")
			(hide yes)
			(effects
				(font
					(size 1.27 1.27)
				)
			)
		)
		(property "Value" "SC1U6D3V3KX-2GP"
			(at -0.0254 -2.0193 0)
			(unlocked yes)
			(layer "F.Fab")
			(hide yes)
			(effects
				(font
					(size 1.016 1.016)
					(thickness 0.1524)
				)
			)
		)
		(property "Device Type" "C603H36"
			(at -0.0254 -3.5433 0)
			(unlocked yes)
			(layer "F.Fab")
			(hide yes)
			(effects
				(font
					(size 1.016 1.016)
					(thickness 0.1524)
				)
			)
		)
		(duplicate_pad_numbers_are_jumpers no)
		(fp_line
			(start -0.4064 0)
			(end 0.4064 0)
			(stroke
				(width 0.2286)
				(type default)
			)
			(layer "F.SilkS")
		)
		(fp_rect
			(start -0.635 1.1811)
			(end 0.635 -1.1811)
			(stroke
				(width 0)
				(type default)
			)
			(fill no)
			(layer "F.CrtYd")
		)
		(fp_rect
			(start -0.635 1.1811)
			(end 0.635 -1.1811)
			(stroke
				(width 0)
				(type default)
			)
			(fill no)
			(layer "F.Fab")
		)
		(pad "1" smd custom
			(at 0 -0.6604)
			(size 0.19685 0.19685)
			(layers "F.Cu" "F.Mask" "F.Paste")
			(net "DDR3_M_A_VREF_DQ1")
			(options
				(clearance outline)
				(anchor circle)
			)
			(primitives
				(gr_poly
					(pts
						(arc
							(start 0.508 -0.2921)
							(mid 0.478242 -0.363942)
							(end 0.4064 -0.3937)
						)
						(arc
							(start -0.4064 -0.3937)
							(mid -0.478242 -0.363942)
							(end -0.508 -0.2921)
						)
						(arc
							(start -0.508 0.2921)
							(mid -0.478242 0.363942)
							(end -0.4064 0.3937)
						)
						(arc
							(start 0.4064 0.3937)
							(mid 0.478242 0.363942)
							(end 0.508 0.2921)
						)
					)
					(width 0)
					(fill yes)
				)
			)
		)
		(pad "2" smd custom
			(at 0 0.6604)
			(size 0.19685 0.19685)
			(layers "F.Cu" "F.Mask" "F.Paste")
			(net "GND")
			(options
				(clearance outline)
				(anchor circle)
			)
			(primitives
				(gr_poly
					(pts
						(arc
							(start 0.508 -0.2921)
							(mid 0.478242 -0.363942)
							(end 0.4064 -0.3937)
						)
						(arc
							(start -0.4064 -0.3937)
							(mid -0.478242 -0.363942)
							(end -0.508 -0.2921)
						)
						(arc
							(start -0.508 0.2921)
							(mid -0.478242 0.363942)
							(end -0.4064 0.3937)
						)
						(arc
							(start 0.4064 0.3937)
							(mid 0.478242 0.363942)
							(end 0.508 0.2921)
						)
					)
					(width 0)
					(fill yes)
				)
			)
		)
	)
	(footprint ""
		(layer "F.Cu")
		(at 8.509 -57.404 90)
		(property "Reference" "C44"
			(at 0 0 90)
			(layer "F.SilkS")
			(hide yes)
			(effects
				(font
					(size 1.27 1.27)
				)
			)
		)
		(property "Value" "SCD1U16V2KX-3GP"
			(at 1.1811 -2.7051 90)
			(unlocked yes)
			(layer "F.Fab")
			(hide yes)
			(effects
				(font
					(size 1.016 1.016)
					(thickness 0.1524)
				)
			)
		)
		(property "Device Type" "C402H22"
			(at 1.1811 -4.2291 90)
			(unlocked yes)
			(layer "F.Fab")
			(hide yes)
			(effects
				(font
					(size 1.016 1.016)
					(thickness 0.1524)
				)
			)
		)
		(duplicate_pad_numbers_are_jumpers no)
		(fp_rect
			(start -0.381 0.7366)
			(end 0.381 -0.7366)
			(stroke
				(width 0)
				(type default)
			)
			(fill no)
			(layer "F.CrtYd")
		)
		(fp_rect
			(start -0.381 0.7366)
			(end 0.381 -0.7366)
			(stroke
				(width 0)
				(type default)
			)
			(fill no)
			(layer "F.Fab")
		)
		(pad "1" smd custom
			(at 0 -0.4572 90)
			(size 0.1143 0.1143)
			(layers "F.Cu" "F.Mask" "F.Paste")
			(net "P2E_CPU_NGFF_C_RX_DP13")
			(options
				(clearance outline)
				(anchor circle)
			)
			(primitives
				(gr_poly
					(pts
						(arc
							(start -0.254 -0.1778)
							(mid -0.239121 -0.213721)
							(end -0.2032 -0.2286)
						)
						(arc
							(start 0.2032 -0.2286)
							(mid 0.239121 -0.213721)
							(end 0.254 -0.1778)
						)
						(arc
							(start 0.254 0.1778)
							(mid 0.239121 0.213721)
							(end 0.2032 0.2286)
						)
						(arc
							(start -0.2032 0.2286)
							(mid -0.239121 0.213721)
							(end -0.254 0.1778)
						)
					)
					(width 0)
					(fill yes)
				)
			)
		)
		(pad "2" smd custom
			(at 0 0.4572 90)
			(size 0.1143 0.1143)
			(layers "F.Cu" "F.Mask" "F.Paste")
			(net "P2E_CPU_NGFF_RX_DP13")
			(options
				(clearance outline)
				(anchor circle)
			)
			(primitives
				(gr_poly
					(pts
						(arc
							(start -0.254 -0.1778)
							(mid -0.239121 -0.213721)
							(end -0.2032 -0.2286)
						)
						(arc
							(start 0.2032 -0.2286)
							(mid 0.239121 -0.213721)
							(end 0.254 -0.1778)
						)
						(arc
							(start 0.254 0.1778)
							(mid 0.239121 0.213721)
							(end 0.2032 0.2286)
						)
						(arc
							(start -0.2032 0.2286)
							(mid -0.239121 0.213721)
							(end -0.254 0.1778)
						)
					)
					(width 0)
					(fill yes)
				)
			)
		)
	)
	(footprint ""
		(layer "F.Cu")
		(at 119.8118 -63.373 -90)
		(property "Reference" "C110"
			(at 0 0 270)
			(layer "F.SilkS")
			(hide yes)
			(effects
				(font
					(size 1.27 1.27)
				)
			)
		)
		(property "Value" "SC10U6D3V3MX-GP"
			(at 0 -2.8194 270)
			(unlocked yes)
			(layer "F.Fab")
			(hide yes)
			(effects
				(font
					(size 1.016 1.016)
					(thickness 0.1524)
				)
			)
		)
		(property "Device Type" "C603H38"
			(at 0 -4.3434 270)
			(unlocked yes)
			(layer "F.Fab")
			(hide yes)
			(effects
				(font
					(size 1.016 1.016)
					(thickness 0.1524)
				)
			)
		)
		(duplicate_pad_numbers_are_jumpers no)
		(fp_line
			(start -0.4064 0)
			(end 0.4064 0)
			(stroke
				(width 0.2286)
				(type default)
			)
			(layer "F.SilkS")
		)
		(fp_rect
			(start -0.635 1.1811)
			(end 0.635 -1.1811)
			(stroke
				(width 0)
				(type default)
			)
			(fill no)
			(layer "F.CrtYd")
		)
		(fp_rect
			(start -0.635 1.1811)
			(end 0.635 -1.1811)
			(stroke
				(width 0)
				(type default)
			)
			(fill no)
			(layer "F.Fab")
		)
		(pad "1" smd custom
			(at 0 -0.6604 270)
			(size 0.19685 0.19685)
			(layers "F.Cu" "F.Mask" "F.Paste")
			(net "PV_VTT_DDR_A")
			(options
				(clearance outline)
				(anchor circle)
			)
			(primitives
				(gr_poly
					(pts
						(arc
							(start 0.508 -0.2921)
							(mid 0.478242 -0.363942)
							(end 0.4064 -0.3937)
						)
						(arc
							(start -0.4064 -0.3937)
							(mid -0.478242 -0.363942)
							(end -0.508 -0.2921)
						)
						(arc
							(start -0.508 0.2921)
							(mid -0.478242 0.363942)
							(end -0.4064 0.3937)
						)
						(arc
							(start 0.4064 0.3937)
							(mid 0.478242 0.363942)
							(end 0.508 0.2921)
						)
					)
					(width 0)
					(fill yes)
				)
			)
		)
		(pad "2" smd custom
			(at 0 0.6604 270)
			(size 0.19685 0.19685)
			(layers "F.Cu" "F.Mask" "F.Paste")
			(net "GND")
			(options
				(clearance outline)
				(anchor circle)
			)
			(primitives
				(gr_poly
					(pts
						(arc
							(start 0.508 -0.2921)
							(mid 0.478242 -0.363942)
							(end 0.4064 -0.3937)
						)
						(arc
							(start -0.4064 -0.3937)
							(mid -0.478242 -0.363942)
							(end -0.508 -0.2921)
						)
						(arc
							(start -0.508 0.2921)
							(mid -0.478242 0.363942)
							(end -0.4064 0.3937)
						)
						(arc
							(start 0.4064 0.3937)
							(mid 0.478242 0.363942)
							(end 0.508 0.2921)
						)
					)
					(width 0)
					(fill yes)
				)
			)
		)
	)
	(footprint ""
		(layer "F.Cu")
		(at 204.597 -33.782)
		(property "Reference" "PRT2"
			(at 0 0 0)
			(layer "F.SilkS")
			(hide yes)
			(effects
				(font
					(size 1.27 1.27)
				)
			)
		)
		(property "Value" "NTC-100K-11-GP-U"
			(at 1.6256 -1.6637 0)
			(unlocked yes)
			(layer "F.Fab")
			(hide yes)
			(effects
				(font
					(size 1.016 1.016)
					(thickness 0.1524)
				)
			)
		)
		(property "Device Type" "NTC-402H24-U"
			(at 1.6256 -3.1877 0)
			(unlocked yes)
			(layer "F.Fab")
			(hide yes)
			(effects
				(font
					(size 1.016 1.016)
					(thickness 0.1524)
				)
			)
		)
		(duplicate_pad_numbers_are_jumpers no)
		(fp_rect
			(start -0.381 0.8382)
			(end 0.381 -0.8382)
			(stroke
				(width 0)
				(type default)
			)
			(fill no)
			(layer "F.CrtYd")
		)
		(fp_rect
			(start -0.381 0.8382)
			(end 0.381 -0.8382)
			(stroke
				(width 0)
				(type default)
			)
			(fill no)
			(layer "F.Fab")
		)
		(pad "1" smd custom
			(at 0 -0.4318)
			(size 0.127 0.127)
			(layers "F.Cu" "F.Mask" "F.Paste")
			(net "GND")
			(options
				(clearance outline)
				(anchor circle)
			)
			(primitives
				(gr_poly
					(pts
						(arc
							(start -0.2032 -0.2794)
							(mid -0.239121 -0.264521)
							(end -0.254 -0.2286)
						)
						(arc
							(start -0.254 0.2286)
							(mid -0.239121 0.264521)
							(end -0.2032 0.2794)
						)
						(arc
							(start 0.2032 0.2794)
							(mid 0.239121 0.264521)
							(end 0.254 0.2286)
						)
						(arc
							(start 0.254 -0.2286)
							(mid 0.239121 -0.264521)
							(end 0.2032 -0.2794)
						)
					)
					(width 0)
					(fill yes)
				)
			)
		)
		(pad "2" smd custom
			(at 0 0.4318)
			(size 0.127 0.127)
			(layers "F.Cu" "F.Mask" "F.Paste")
			(net "VR_PVDDR_A_NTC_R")
			(options
				(clearance outline)
				(anchor circle)
			)
			(primitives
				(gr_poly
					(pts
						(arc
							(start -0.2032 -0.2794)
							(mid -0.239121 -0.264521)
							(end -0.254 -0.2286)
						)
						(arc
							(start -0.254 0.2286)
							(mid -0.239121 0.264521)
							(end -0.2032 0.2794)
						)
						(arc
							(start 0.2032 0.2794)
							(mid 0.239121 0.264521)
							(end 0.254 0.2286)
						)
						(arc
							(start 0.254 -0.2286)
							(mid 0.239121 -0.264521)
							(end 0.2032 -0.2794)
						)
					)
					(width 0)
					(fill yes)
				)
			)
		)
	)
	(footprint ""
		(layer "F.Cu")
		(at 30.734 -55.245 180)
		(property "Reference" "PC56"
			(at 0 0 180)
			(layer "F.SilkS")
			(hide yes)
			(effects
				(font
					(size 1.27 1.27)
				)
			)
		)
		(property "Value" "SCD22U16V3KX-2-GP"
			(at -0.0254 -2.0193 180)
			(unlocked yes)
			(layer "F.Fab")
			(hide yes)
			(effects
				(font
					(size 1.016 1.016)
					(thickness 0.1524)
				)
			)
		)
		(property "Device Type" "C603H36"
			(at -0.0254 -3.5433 180)
			(unlocked yes)
			(layer "F.Fab")
			(hide yes)
			(effects
				(font
					(size 1.016 1.016)
					(thickness 0.1524)
				)
			)
		)
		(duplicate_pad_numbers_are_jumpers no)
		(fp_line
			(start -0.4064 0)
			(end 0.4064 0)
			(stroke
				(width 0.2286)
				(type default)
			)
			(layer "F.SilkS")
		)
		(fp_rect
			(start -0.635 1.1811)
			(end 0.635 -1.1811)
			(stroke
				(width 0)
				(type default)
			)
			(fill no)
			(layer "F.CrtYd")
		)
		(fp_rect
			(start -0.635 1.1811)
			(end 0.635 -1.1811)
			(stroke
				(width 0)
				(type default)
			)
			(fill no)
			(layer "F.Fab")
		)
		(pad "1" smd custom
			(at 0 -0.6604 180)
			(size 0.19685 0.19685)
			(layers "F.Cu" "F.Mask" "F.Paste")
			(net "VR_PVCCP_PVNN_VIN")
			(options
				(clearance outline)
				(anchor circle)
			)
			(primitives
				(gr_poly
					(pts
						(arc
							(start 0.508 -0.2921)
							(mid 0.478242 -0.363942)
							(end 0.4064 -0.3937)
						)
						(arc
							(start -0.4064 -0.3937)
							(mid -0.478242 -0.363942)
							(end -0.508 -0.2921)
						)
						(arc
							(start -0.508 0.2921)
							(mid -0.478242 0.363942)
							(end -0.4064 0.3937)
						)
						(arc
							(start 0.4064 0.3937)
							(mid 0.478242 0.363942)
							(end 0.508 0.2921)
						)
					)
					(width 0)
					(fill yes)
				)
			)
		)
		(pad "2" smd custom
			(at 0 0.6604 180)
			(size 0.19685 0.19685)
			(layers "F.Cu" "F.Mask" "F.Paste")
			(net "GND")
			(options
				(clearance outline)
				(anchor circle)
			)
			(primitives
				(gr_poly
					(pts
						(arc
							(start 0.508 -0.2921)
							(mid 0.478242 -0.363942)
							(end 0.4064 -0.3937)
						)
						(arc
							(start -0.4064 -0.3937)
							(mid -0.478242 -0.363942)
							(end -0.508 -0.2921)
						)
						(arc
							(start -0.508 0.2921)
							(mid -0.478242 0.363942)
							(end -0.4064 0.3937)
						)
						(arc
							(start 0.4064 0.3937)
							(mid 0.478242 0.363942)
							(end 0.508 0.2921)
						)
					)
					(width 0)
					(fill yes)
				)
			)
		)
	)
)
